(kicad_pcb
	(version 20260206)
	(generator "pcbnew")
	(generator_version "10.0")
	(general
		(thickness 1.6)
		(legacy_teardrops no)
	)
	(paper "A4")
	(title_block
		(title "Wiwynn_Tioga_Pass_MB.brd")
		(comment 1 "Tioga Pass / footprint 1664 of 4770 (U7C1), pads 230-344 of 1310")
	)
	(layers
		(0 "F.Cu" signal "TOP")
		(4 "In1.Cu" signal "L2GND")
		(6 "In2.Cu" signal "L3")
		(8 "In3.Cu" signal "L4GND")
		(10 "In4.Cu" signal "L5")
		(12 "In5.Cu" signal "L6GND")
		(14 "In6.Cu" signal "L7VCC")
		(16 "In7.Cu" signal "L8VCC")
		(18 "In8.Cu" signal "L9GND")
		(20 "In9.Cu" signal "L10")
		(22 "In10.Cu" signal "L11GND")
		(24 "In11.Cu" signal "L12")
		(26 "In12.Cu" signal "L13GND")
		(2 "B.Cu" signal "BOTTOM")
		(9 "F.Adhes" user "F.Adhesive")
		(11 "B.Adhes" user "B.Adhesive")
		(13 "F.Paste" user "Package Geometry/Pastemask Top")
		(15 "B.Paste" user "Package Geometry/Pastemask Bottom")
		(5 "F.SilkS" user "Ref Des/Silkscreen Top")
		(7 "B.SilkS" user "Ref Des/Silkscreen Bottom")
		(1 "F.Mask" user "Board Geometry/Soldermask Top")
		(3 "B.Mask" user "Board Geometry/Soldermask Bottom")
		(17 "Dwgs.User" user "User.Drawings")
		(19 "Cmts.User" user "User.Comments")
		(21 "Eco1.User" user "User.Eco1")
		(23 "Eco2.User" user "User.Eco2")
		(25 "Edge.Cuts" user "Board Geometry/Outline")
		(27 "Margin" user)
		(31 "F.CrtYd" user "Package Geometry/Place Bound Top")
		(29 "B.CrtYd" user "Package Geometry/Place Bound Bottom")
		(35 "F.Fab" user "Ref Des/Assembly Top")
		(33 "B.Fab" user "Ref Des/Assembly Bottom")
	)
	(footprint ""
		(layer "F.Cu")
		(at 387.985 -109.855 90)
		(property "Reference" "U7C1"
			(at 17.75333 -13.335 0)
			(unlocked yes)
			(layer "F.SilkS")
			(effects
				(font
					(size 0.7874 0.5842)
					(thickness 0.1524)
				)
				(justify left)
			)
		)
		(property "Value" ""
			(at 0 0 90)
			(layer "F.Fab")
			(effects
				(font
					(size 1.27 1.27)
				)
			)
		)
		(duplicate_pad_numbers_are_jumpers no)
		(pad "AK26" smd circle
			(at -5.20065 -0.24765 180)
			(size 0.381 0.381)
			(layers "F.Cu" "F.Mask" "F.Paste")
			(net "GND")
		)
		(pad "AK27" smd circle
			(at -4.40055 -0.24765 180)
			(size 0.381 0.381)
			(layers "F.Cu" "F.Mask" "F.Paste")
			(net "P1V05_PCH_STBY")
		)
		(pad "AK29" smd circle
			(at -3.60045 -0.24765 180)
			(size 0.381 0.381)
			(layers "F.Cu" "F.Mask" "F.Paste")
			(net "P1V8_PCH_STBY")
		)
		(pad "AK30" smd circle
			(at -2.80035 -0.24765 180)
			(size 0.381 0.381)
			(layers "F.Cu" "F.Mask" "F.Paste")
			(net "GND")
		)
		(pad "AK32" smd circle
			(at -2.00025 -0.24765 180)
			(size 0.381 0.381)
			(layers "F.Cu" "F.Mask" "F.Paste")
			(net "PVNN_PCH_STBY")
		)
		(pad "AK34" smd circle
			(at -1.20015 -0.24765 180)
			(size 0.381 0.381)
			(layers "F.Cu" "F.Mask" "F.Paste")
			(net "PVNN_PCH_STBY")
		)
		(pad "AK36" smd circle
			(at -0.40005 -0.24765 180)
			(size 0.381 0.381)
			(layers "F.Cu" "F.Mask" "F.Paste")
			(net "VSENSE_PVNN_PCH_STBY_FPK")
		)
		(pad "AK37" smd circle
			(at 0.40005 -0.24765 180)
			(size 0.381 0.381)
			(layers "F.Cu" "F.Mask" "F.Paste")
			(net "PVNN_PCH_STBY")
		)
		(pad "AK39" smd circle
			(at 1.20015 -0.24765 180)
			(size 0.381 0.381)
			(layers "F.Cu" "F.Mask" "F.Paste")
			(net "PVNN_PCH_STBY")
		)
		(pad "AK41" smd circle
			(at 2.00025 -0.24765 180)
			(size 0.381 0.381)
			(layers "F.Cu" "F.Mask" "F.Paste")
			(net "GND")
		)
		(pad "AK43" smd circle
			(at 2.80035 -0.24765 180)
			(size 0.381 0.381)
			(layers "F.Cu" "F.Mask" "F.Paste")
			(net "P1V05_PCH_STBY")
		)
		(pad "AK45" smd circle
			(at 3.60045 -0.24765 180)
			(size 0.381 0.381)
			(layers "F.Cu" "F.Mask" "F.Paste")
			(net "P1V05_PCH_STBY")
		)
		(pad "AK46" smd circle
			(at 4.40055 -0.24765 180)
			(size 0.381 0.381)
			(layers "F.Cu" "F.Mask" "F.Paste")
			(net "GND")
		)
		(pad "AK48" smd circle
			(at 5.20065 -0.24765 180)
			(size 0.381 0.381)
			(layers "F.Cu" "F.Mask" "F.Paste")
			(net "GND")
		)
		(pad "AK50" smd circle
			(at 6.00964 -0.24765)
			(size 0.381 0.381)
			(layers "F.Cu" "F.Mask" "F.Paste")
			(net "P1V05_PCH_STBY_WM20_PLL")
		)
		(pad "AK54" smd circle
			(at 7.72668 -0.24765)
			(size 0.381 0.381)
			(layers "F.Cu" "F.Mask" "F.Paste")
			(net "TP_PCH_RSVD36")
		)
		(pad "AK58" smd circle
			(at 9.44372 -0.24765)
			(size 0.381 0.381)
			(layers "F.Cu" "F.Mask" "F.Paste")
			(net "GND")
		)
		(pad "AK61" smd circle
			(at 11.16076 -0.24765)
			(size 0.381 0.381)
			(layers "F.Cu" "F.Mask" "F.Paste")
			(net "GND")
		)
		(pad "AK65" smd circle
			(at 12.8778 -0.24765)
			(size 0.381 0.381)
			(layers "F.Cu" "F.Mask" "F.Paste")
			(net "SATA6G_PCH_PCIE_UP_SATA_RXN<2>")
		)
		(pad "AK69" smd circle
			(at 15.064994 -0.500126)
			(size 0.3048 0.3048)
			(layers "F.Cu" "F.Mask" "F.Paste")
			(net "GND")
		)
		(pad "AK71" smd circle
			(at 15.895066 -0.500126)
			(size 0.3048 0.3048)
			(layers "F.Cu" "F.Mask" "F.Paste")
			(net "GND")
		)
		(pad "AL1" smd oval
			(at -16.310102 0 180)
			(size 0.254 0.3302)
			(layers "F.Cu" "F.Mask" "F.Paste")
			(net "RMII_SPRNGVLLE_BMC_PCH_RXD0_R1")
		)
		(pad "AL3" smd circle
			(at -15.48003 0 180)
			(size 0.3048 0.3048)
			(layers "F.Cu" "F.Mask" "F.Paste")
			(net "RMII_BMC_PCH_SPRNGVLLE_TXEN")
		)
		(pad "AL5" smd circle
			(at -14.649958 0 180)
			(size 0.3048 0.3048)
			(layers "F.Cu" "F.Mask" "F.Paste")
			(net "GND")
		)
		(pad "AL7" smd circle
			(at -13.73632 0.24765)
			(size 0.381 0.381)
			(layers "F.Cu" "F.Mask" "F.Paste")
			(net "SGPIO_PCH_SATA_CLOCK")
		)
		(pad "AL11" smd circle
			(at -12.01928 0.24765)
			(size 0.381 0.381)
			(layers "F.Cu" "F.Mask" "F.Paste")
			(net "LED_PCH_SSATA_HDD_N")
		)
		(pad "AL15" smd circle
			(at -10.30224 0.24765)
			(size 0.381 0.381)
			(layers "F.Cu" "F.Mask" "F.Paste")
			(net "FM_MEM_THERM_EVENT_PCH_N")
		)
		(pad "AL18" smd circle
			(at -8.5852 0.24765)
			(size 0.381 0.381)
			(layers "F.Cu" "F.Mask" "F.Paste")
			(net "JTAG_PCH_PLD_TCK")
		)
		(pad "AL22" smd circle
			(at -6.86816 0.24765)
			(size 0.381 0.381)
			(layers "F.Cu" "F.Mask" "F.Paste")
			(net "GND")
		)
		(pad "AL52" smd circle
			(at 6.86816 0.24765)
			(size 0.381 0.381)
			(layers "F.Cu" "F.Mask" "F.Paste")
			(net "GND")
		)
		(pad "AL56" smd circle
			(at 8.5852 0.24765)
			(size 0.381 0.381)
			(layers "F.Cu" "F.Mask" "F.Paste")
			(net "XDP_PCH_TCK1")
		)
		(pad "AL59" smd circle
			(at 10.30224 0.24765)
			(size 0.381 0.381)
			(layers "F.Cu" "F.Mask" "F.Paste")
			(net "GND")
		)
		(pad "AL63" smd circle
			(at 12.01928 0.24765)
			(size 0.381 0.381)
			(layers "F.Cu" "F.Mask" "F.Paste")
			(net "SATA6G_PCH_PCIE_UP_SATA_RXP<3>")
		)
		(pad "AL66" smd circle
			(at 13.73632 0.24765)
			(size 0.381 0.381)
			(layers "F.Cu" "F.Mask" "F.Paste")
			(net "SATA6G_PCH_PCIE_UP_SATA_RXN<1>")
		)
		(pad "AL68" smd circle
			(at 14.649958 0)
			(size 0.3048 0.3048)
			(layers "F.Cu" "F.Mask" "F.Paste")
			(net "GND")
		)
		(pad "AL70" smd circle
			(at 15.48003 0)
			(size 0.3048 0.3048)
			(layers "F.Cu" "F.Mask" "F.Paste")
			(net "GND")
		)
		(pad "AL72" smd oval
			(at 16.310102 0 180)
			(size 0.254 0.3302)
			(layers "F.Cu" "F.Mask" "F.Paste")
			(net "GND")
		)
		(pad "AM2" smd circle
			(at -15.895066 0.500126 180)
			(size 0.3048 0.3048)
			(layers "F.Cu" "F.Mask" "F.Paste")
			(net "RMII_BMC_PCH_SPRNGVLLE_TXD0")
		)
		(pad "AM4" smd circle
			(at -15.064994 0.500126 180)
			(size 0.3048 0.3048)
			(layers "F.Cu" "F.Mask" "F.Paste")
			(net "A_1P8_3P3_RCOMP")
		)
		(pad "AM26" smd circle
			(at -5.20065 0.55245 180)
			(size 0.381 0.381)
			(layers "F.Cu" "F.Mask" "F.Paste")
			(net "GND")
		)
		(pad "AM27" smd circle
			(at -4.40055 0.55245 180)
			(size 0.381 0.381)
			(layers "F.Cu" "F.Mask" "F.Paste")
			(net "P1V05_PCH_STBY")
		)
		(pad "AM29" smd circle
			(at -3.60045 0.55245 180)
			(size 0.381 0.381)
			(layers "F.Cu" "F.Mask" "F.Paste")
			(net "P1V8_PCH_STBY")
		)
		(pad "AM30" smd circle
			(at -2.80035 0.55245 180)
			(size 0.381 0.381)
			(layers "F.Cu" "F.Mask" "F.Paste")
			(net "GND")
		)
		(pad "AM32" smd circle
			(at -2.00025 0.55245 180)
			(size 0.381 0.381)
			(layers "F.Cu" "F.Mask" "F.Paste")
			(net "PVNN_PCH_STBY")
		)
		(pad "AM34" smd circle
			(at -1.20015 0.55245 180)
			(size 0.381 0.381)
			(layers "F.Cu" "F.Mask" "F.Paste")
			(net "PVNN_PCH_STBY")
		)
		(pad "AM36" smd circle
			(at -0.40005 0.55245 180)
			(size 0.381 0.381)
			(layers "F.Cu" "F.Mask" "F.Paste")
			(net "PVNN_PCH_STBY")
		)
		(pad "AM37" smd circle
			(at 0.40005 0.55245 180)
			(size 0.381 0.381)
			(layers "F.Cu" "F.Mask" "F.Paste")
			(net "PVNN_PCH_STBY")
		)
		(pad "AM39" smd circle
			(at 1.20015 0.55245 180)
			(size 0.381 0.381)
			(layers "F.Cu" "F.Mask" "F.Paste")
			(net "PVNN_PCH_STBY")
		)
		(pad "AM41" smd circle
			(at 2.00025 0.55245 180)
			(size 0.381 0.381)
			(layers "F.Cu" "F.Mask" "F.Paste")
			(net "GND")
		)
		(pad "AM43" smd circle
			(at 2.80035 0.55245 180)
			(size 0.381 0.381)
			(layers "F.Cu" "F.Mask" "F.Paste")
			(net "P1V05_PCH_STBY")
		)
		(pad "AM45" smd circle
			(at 3.60045 0.55245 180)
			(size 0.381 0.381)
			(layers "F.Cu" "F.Mask" "F.Paste")
			(net "P1V05_PCH_STBY")
		)
		(pad "AM46" smd circle
			(at 4.40055 0.55245 180)
			(size 0.381 0.381)
			(layers "F.Cu" "F.Mask" "F.Paste")
			(net "GND")
		)
		(pad "AM48" smd circle
			(at 5.20065 0.55245 180)
			(size 0.381 0.381)
			(layers "F.Cu" "F.Mask" "F.Paste")
			(net "P1V05_PCH_STBY")
		)
		(pad "AM69" smd circle
			(at 15.064994 0.500126)
			(size 0.3048 0.3048)
			(layers "F.Cu" "F.Mask" "F.Paste")
			(net "PE_PCH_SPRV_RX_C_DN")
		)
		(pad "AM71" smd circle
			(at 15.895066 0.500126)
			(size 0.3048 0.3048)
			(layers "F.Cu" "F.Mask" "F.Paste")
			(net "PE_PCH_SPRV_RX_C_DP")
		)
		(pad "AN1" smd oval
			(at -16.310102 0.999998 180)
			(size 0.254 0.3302)
			(layers "F.Cu" "F.Mask" "F.Paste")
			(net "RMII_SPRNGVLLE_BMC_PCH_RXD1_R1")
		)
		(pad "AN3" smd circle
			(at -15.48003 0.999998 180)
			(size 0.3048 0.3048)
			(layers "F.Cu" "F.Mask" "F.Paste")
			(net "RMII_BMC_PCH_SPRNGVLLE_CRSDV_R1")
		)
		(pad "AN5" smd circle
			(at -14.649958 0.999998 180)
			(size 0.3048 0.3048)
			(layers "F.Cu" "F.Mask" "F.Paste")
			(net "GND")
		)
		(pad "AN9" smd circle
			(at -12.8778 0.74295)
			(size 0.381 0.381)
			(layers "F.Cu" "F.Mask" "F.Paste")
			(net "GND")
		)
		(pad "AN13" smd circle
			(at -11.16076 0.74295)
			(size 0.381 0.381)
			(layers "F.Cu" "F.Mask" "F.Paste")
			(net "GND")
		)
		(pad "AN17" smd circle
			(at -9.44372 0.74295)
			(size 0.381 0.381)
			(layers "F.Cu" "F.Mask" "F.Paste")
			(net "GND")
		)
		(pad "AN20" smd circle
			(at -7.72668 0.74295)
			(size 0.381 0.381)
			(layers "F.Cu" "F.Mask" "F.Paste")
			(net "GND")
		)
		(pad "AN24" smd circle
			(at -6.00964 0.74295)
			(size 0.381 0.381)
			(layers "F.Cu" "F.Mask" "F.Paste")
			(net "P3V3_STBY")
		)
		(pad "AN50" smd circle
			(at 6.00964 0.74295)
			(size 0.381 0.381)
			(layers "F.Cu" "F.Mask" "F.Paste")
			(net "P1V05_PCH_STBY_WM20_PLL")
		)
		(pad "AN54" smd circle
			(at 7.72668 0.74295)
			(size 0.381 0.381)
			(layers "F.Cu" "F.Mask" "F.Paste")
			(net "XDP_TDI")
		)
		(pad "AN58" smd circle
			(at 9.44372 0.74295)
			(size 0.381 0.381)
			(layers "F.Cu" "F.Mask" "F.Paste")
			(net "GND")
		)
		(pad "AN61" smd circle
			(at 11.16076 0.74295)
			(size 0.381 0.381)
			(layers "F.Cu" "F.Mask" "F.Paste")
			(net "SATA6G_PCH_PCIE_UP_SATA_RXP<6>")
		)
		(pad "AN65" smd circle
			(at 12.8778 0.74295)
			(size 0.381 0.381)
			(layers "F.Cu" "F.Mask" "F.Paste")
			(net "SATA6G_PCH_PCIE_UP_SATA_RXP<1>")
		)
		(pad "AN68" smd circle
			(at 14.649958 0.999998)
			(size 0.3048 0.3048)
			(layers "F.Cu" "F.Mask" "F.Paste")
			(net "GND")
		)
		(pad "AN70" smd circle
			(at 15.48003 0.999998)
			(size 0.3048 0.3048)
			(layers "F.Cu" "F.Mask" "F.Paste")
			(net "P2E_SSB_BMC_RX_C_DN")
		)
		(pad "AN72" smd oval
			(at 16.310102 0.999998 180)
			(size 0.254 0.3302)
			(layers "F.Cu" "F.Mask" "F.Paste")
			(net "P2E_SSB_BMC_RX_C_DP")
		)
		(pad "AP2" smd circle
			(at -15.895066 1.500124 180)
			(size 0.3048 0.3048)
			(layers "F.Cu" "F.Mask" "F.Paste")
			(net "GND")
		)
		(pad "AP4" smd circle
			(at -15.064994 1.500124 180)
			(size 0.3048 0.3048)
			(layers "F.Cu" "F.Mask" "F.Paste")
			(net "GND")
		)
		(pad "AP7" smd circle
			(at -13.73632 1.23825)
			(size 0.381 0.381)
			(layers "F.Cu" "F.Mask" "F.Paste")
			(net "IRQ_SML1_PMBUS_ALERT_R1_N")
		)
		(pad "AP11" smd circle
			(at -12.01928 1.23825)
			(size 0.381 0.381)
			(layers "F.Cu" "F.Mask" "F.Paste")
			(net "SGPIO_PCH_SATA_DOUT0")
		)
		(pad "AP15" smd circle
			(at -10.30224 1.23825)
			(size 0.381 0.381)
			(layers "F.Cu" "F.Mask" "F.Paste")
			(net "FM_BIOS_TOP_SWAP")
		)
		(pad "AP18" smd circle
			(at -8.5852 1.23825)
			(size 0.381 0.381)
			(layers "F.Cu" "F.Mask" "F.Paste")
			(net "SGPIO_PCH_SSATA_CLOCK")
		)
		(pad "AP22" smd circle
			(at -6.86816 1.23825)
			(size 0.381 0.381)
			(layers "F.Cu" "F.Mask" "F.Paste")
			(net "GND")
		)
		(pad "AP26" smd circle
			(at -5.20065 1.35255 180)
			(size 0.381 0.381)
			(layers "F.Cu" "F.Mask" "F.Paste")
			(net "GND")
		)
		(pad "AP27" smd circle
			(at -4.40055 1.35255 180)
			(size 0.381 0.381)
			(layers "F.Cu" "F.Mask" "F.Paste")
			(net "TP_PCH_RSVD58")
		)
		(pad "AP29" smd circle
			(at -3.60045 1.35255 180)
			(size 0.381 0.381)
			(layers "F.Cu" "F.Mask" "F.Paste")
			(net "P1V8_PCH_STBY")
		)
		(pad "AP30" smd circle
			(at -2.80035 1.35255 180)
			(size 0.381 0.381)
			(layers "F.Cu" "F.Mask" "F.Paste")
			(net "GND")
		)
		(pad "AP32" smd circle
			(at -2.00025 1.35255 180)
			(size 0.381 0.381)
			(layers "F.Cu" "F.Mask" "F.Paste")
			(net "PVNN_PCH_STBY")
		)
		(pad "AP34" smd circle
			(at -1.20015 1.35255 180)
			(size 0.381 0.381)
			(layers "F.Cu" "F.Mask" "F.Paste")
			(net "PVNN_PCH_STBY")
		)
		(pad "AP36" smd circle
			(at -0.40005 1.35255 180)
			(size 0.381 0.381)
			(layers "F.Cu" "F.Mask" "F.Paste")
			(net "PVNN_PCH_STBY")
		)
		(pad "AP37" smd circle
			(at 0.40005 1.35255 180)
			(size 0.381 0.381)
			(layers "F.Cu" "F.Mask" "F.Paste")
			(net "PVNN_PCH_STBY")
		)
		(pad "AP39" smd circle
			(at 1.20015 1.35255 180)
			(size 0.381 0.381)
			(layers "F.Cu" "F.Mask" "F.Paste")
			(net "PVNN_PCH_STBY")
		)
		(pad "AP41" smd circle
			(at 2.00025 1.35255 180)
			(size 0.381 0.381)
			(layers "F.Cu" "F.Mask" "F.Paste")
			(net "GND")
		)
		(pad "AP43" smd circle
			(at 2.80035 1.35255 180)
			(size 0.381 0.381)
			(layers "F.Cu" "F.Mask" "F.Paste")
			(net "P1V05_PCH_STBY")
		)
		(pad "AP45" smd circle
			(at 3.60045 1.35255 180)
			(size 0.381 0.381)
			(layers "F.Cu" "F.Mask" "F.Paste")
			(net "P1V05_PCH_STBY")
		)
		(pad "AP46" smd circle
			(at 4.40055 1.35255 180)
			(size 0.381 0.381)
			(layers "F.Cu" "F.Mask" "F.Paste")
			(net "GND")
		)
		(pad "AP48" smd circle
			(at 5.20065 1.35255 180)
			(size 0.381 0.381)
			(layers "F.Cu" "F.Mask" "F.Paste")
			(net "P1V05_PCH_STBY_WM26_PLL")
		)
		(pad "AP52" smd circle
			(at 6.86816 1.23825)
			(size 0.381 0.381)
			(layers "F.Cu" "F.Mask" "F.Paste")
			(net "GND")
		)
		(pad "AP56" smd circle
			(at 8.5852 1.23825)
			(size 0.381 0.381)
			(layers "F.Cu" "F.Mask" "F.Paste")
			(net "XDP_TDO")
		)
		(pad "AP59" smd circle
			(at 10.30224 1.23825)
			(size 0.381 0.381)
			(layers "F.Cu" "F.Mask" "F.Paste")
			(net "SATA6G_PCH_PCIE_UP_SATA_RXN<6>")
		)
		(pad "AP63" smd circle
			(at 12.01928 1.23825)
			(size 0.381 0.381)
			(layers "F.Cu" "F.Mask" "F.Paste")
			(net "SATA6G_PCH_PCIE_UP_SATA_RXN<3>")
		)
		(pad "AP66" smd circle
			(at 13.73632 1.23825)
			(size 0.381 0.381)
			(layers "F.Cu" "F.Mask" "F.Paste")
			(net "GND")
		)
		(pad "AP69" smd circle
			(at 15.064994 1.500124)
			(size 0.3048 0.3048)
			(layers "F.Cu" "F.Mask" "F.Paste")
			(net "TP_PCH_RSVD47")
		)
		(pad "AP71" smd circle
			(at 15.895066 1.500124)
			(size 0.3048 0.3048)
			(layers "F.Cu" "F.Mask" "F.Paste")
			(net "TP_PCH_RSVD48")
		)
		(pad "AR1" smd oval
			(at -16.310102 1.999996 180)
			(size 0.254 0.3302)
			(layers "F.Cu" "F.Mask" "F.Paste")
			(net "Net_463")
		)
		(pad "AR3" smd circle
			(at -15.48003 1.999996 180)
			(size 0.3048 0.3048)
			(layers "F.Cu" "F.Mask" "F.Paste")
			(net "Net_458")
		)
		(pad "AR5" smd circle
			(at -14.649958 1.999996 180)
			(size 0.3048 0.3048)
			(layers "F.Cu" "F.Mask" "F.Paste")
			(net "GND")
		)
		(pad "AR9" smd circle
			(at -12.8778 1.73355)
			(size 0.381 0.381)
			(layers "F.Cu" "F.Mask" "F.Paste")
			(net "SGPIO_PCH_SATA_LOAD")
		)
		(pad "AR13" smd circle
			(at -11.16076 1.73355)
			(size 0.381 0.381)
			(layers "F.Cu" "F.Mask" "F.Paste")
			(net "FM_FORCE_ADR_N")
		)
		(pad "AR17" smd circle
			(at -9.44372 1.73355)
			(size 0.381 0.381)
			(layers "F.Cu" "F.Mask" "F.Paste")
			(net "IRQ_PCH_NIC_ALERT_N")
		)
		(pad "AR20" smd circle
			(at -7.72668 1.73355)
			(size 0.381 0.381)
			(layers "F.Cu" "F.Mask" "F.Paste")
			(net "JTAG_PCH_PLD_TDO")
		)
		(pad "AR24" smd circle
			(at -6.00964 1.73355)
			(size 0.381 0.381)
			(layers "F.Cu" "F.Mask" "F.Paste")
			(net "P3V3_STBY")
		)
		(pad "AR50" smd circle
			(at 6.00964 1.73355)
			(size 0.381 0.381)
			(layers "F.Cu" "F.Mask" "F.Paste")
			(net "GND")
		)
		(pad "AR54" smd circle
			(at 7.72668 1.73355)
			(size 0.381 0.381)
			(layers "F.Cu" "F.Mask" "F.Paste")
			(net "XDP_ITP_PMODE")
		)
		(pad "AR58" smd circle
			(at 9.44372 1.73355)
			(size 0.381 0.381)
			(layers "F.Cu" "F.Mask" "F.Paste")
			(net "GND")
		)
		(pad "AR61" smd circle
			(at 11.16076 1.73355)
			(size 0.381 0.381)
			(layers "F.Cu" "F.Mask" "F.Paste")
			(net "SATA6G_PCH_PCIE_UP_SATA_RXN<0>")
		)
		(pad "AR65" smd circle
			(at 12.8778 1.73355)
			(size 0.381 0.381)
			(layers "F.Cu" "F.Mask" "F.Paste")
			(net "GND")
		)
		(pad "AR68" smd circle
			(at 14.649958 1.999996)
			(size 0.3048 0.3048)
			(layers "F.Cu" "F.Mask" "F.Paste")
			(net "GND")
		)
		(pad "AR70" smd circle
			(at 15.48003 1.999996)
			(size 0.3048 0.3048)
			(layers "F.Cu" "F.Mask" "F.Paste")
			(net "GND")
		)
		(pad "AR72" smd oval
			(at 16.310102 1.999996 180)
			(size 0.254 0.3302)
			(layers "F.Cu" "F.Mask" "F.Paste")
			(net "GND")
		)
	)
)
